(kicad_pcb
	(version 20260206)
	(generator "pcbnew")
	(generator_version "10.0")
	(general
		(thickness 1.6)
		(legacy_teardrops no)
	)
	(paper "A4")
	(title_block
		(title "04192023_DAF0TMB3IC0_F0TG_MB_C_brd_V02_OCP.brd")
		(comment 1 "Grand Teton / footprints 2424-2429 of 8354")
	)
	(layers
		(0 "F.Cu" signal "TOP")
		(4 "In1.Cu" signal "GND")
		(6 "In2.Cu" signal "IN1")
		(8 "In3.Cu" signal "GND1")
		(10 "In4.Cu" signal "IN2")
		(12 "In5.Cu" signal "GND2")
		(14 "In6.Cu" signal "IN3")
		(16 "In7.Cu" signal "GND3")
		(18 "In8.Cu" signal "VCC")
		(20 "In9.Cu" signal "VCC1")
		(22 "In10.Cu" signal "GND4")
		(24 "In11.Cu" signal "IN4")
		(26 "In12.Cu" signal "GND5")
		(28 "In13.Cu" signal "IN5")
		(30 "In14.Cu" signal "GND6")
		(32 "In15.Cu" signal "IN6")
		(34 "In16.Cu" signal "GND7")
		(2 "B.Cu" signal "BOTTOM")
		(9 "F.Adhes" user "F.Adhesive")
		(11 "B.Adhes" user "B.Adhesive")
		(13 "F.Paste" user "Package Geometry/Pastemask Top")
		(15 "B.Paste" user "Package Geometry/Pastemask Bottom")
		(5 "F.SilkS" user "Ref Des/Silkscreen Top")
		(7 "B.SilkS" user "Ref Des/Silkscreen Bottom")
		(1 "F.Mask" user "Board Geometry/Soldermask Top")
		(3 "B.Mask" user "Board Geometry/Soldermask Bottom")
		(17 "Dwgs.User" user "User.Drawings")
		(19 "Cmts.User" user "User.Comments")
		(21 "Eco1.User" user "User.Eco1")
		(23 "Eco2.User" user "User.Eco2")
		(25 "Edge.Cuts" user "Board Geometry/Outline")
		(27 "Margin" user)
		(31 "F.CrtYd" user "Package Geometry/Place Bound Top")
		(29 "B.CrtYd" user "Package Geometry/Place Bound Bottom")
		(35 "F.Fab" user "Ref Des/Assembly Top")
		(33 "B.Fab" user "Ref Des/Assembly Bottom")
	)
	(footprint ""
		(layer "F.Cu")
		(at 157.692852 -350.256856 180)
		(property "Reference" "C642"
			(at 0 0 180)
			(layer "F.SilkS")
			(hide yes)
			(effects
				(font
					(size 1.27 1.27)
				)
			)
		)
		(property "Value" ""
			(at 0 0 180)
			(layer "F.Fab")
			(effects
				(font
					(size 1.27 1.27)
				)
			)
		)
		(duplicate_pad_numbers_are_jumpers no)
		(fp_line
			(start 0.7874 0.4064)
			(end -0.7874 0.4064)
			(stroke
				(width 0.1524)
				(type default)
			)
			(layer "F.SilkS")
		)
		(fp_line
			(start 0.7874 -0.4064)
			(end 0.7874 0.4064)
			(stroke
				(width 0.1524)
				(type default)
			)
			(layer "F.SilkS")
		)
		(fp_line
			(start -0.7874 0.4064)
			(end -0.7874 -0.4064)
			(stroke
				(width 0.1524)
				(type default)
			)
			(layer "F.SilkS")
		)
		(fp_line
			(start -0.7874 -0.4064)
			(end 0.7874 -0.4064)
			(stroke
				(width 0.1524)
				(type default)
			)
			(layer "F.SilkS")
		)
		(fp_line
			(start 0.67945 0.3048)
			(end 0.120396 0.3048)
			(stroke
				(width 0.1)
				(type default)
			)
			(layer "F.Fab")
		)
		(fp_line
			(start 0.67945 -0.3048)
			(end 0.67945 0.3048)
			(stroke
				(width 0.1)
				(type default)
			)
			(layer "F.Fab")
		)
		(fp_line
			(start 0.12065 -0.2794)
			(end 0.12065 -0.3048)
			(stroke
				(width 0.1)
				(type default)
			)
			(layer "F.Fab")
		)
		(fp_line
			(start 0.12065 -0.3048)
			(end 0.67945 -0.3048)
			(stroke
				(width 0.1)
				(type default)
			)
			(layer "F.Fab")
		)
		(fp_line
			(start 0.120396 0.3048)
			(end 0.120396 0.2794)
			(stroke
				(width 0.1)
				(type default)
			)
			(layer "F.Fab")
		)
		(fp_line
			(start 0.120396 0.2794)
			(end -0.12065 0.2794)
			(stroke
				(width 0.1)
				(type default)
			)
			(layer "F.Fab")
		)
		(fp_line
			(start -0.12065 0.3048)
			(end -0.67945 0.3048)
			(stroke
				(width 0.1)
				(type default)
			)
			(layer "F.Fab")
		)
		(fp_line
			(start -0.12065 0.2794)
			(end -0.12065 0.3048)
			(stroke
				(width 0.1)
				(type default)
			)
			(layer "F.Fab")
		)
		(fp_line
			(start -0.12065 -0.2794)
			(end 0.12065 -0.2794)
			(stroke
				(width 0.1)
				(type default)
			)
			(layer "F.Fab")
		)
		(fp_line
			(start -0.12065 -0.305054)
			(end -0.12065 -0.2794)
			(stroke
				(width 0.1)
				(type default)
			)
			(layer "F.Fab")
		)
		(fp_line
			(start -0.67945 0.3048)
			(end -0.67945 -0.305054)
			(stroke
				(width 0.1)
				(type default)
			)
			(layer "F.Fab")
		)
		(fp_line
			(start -0.67945 -0.305054)
			(end -0.12065 -0.305054)
			(stroke
				(width 0.1)
				(type default)
			)
			(layer "F.Fab")
		)
		(pad "1" smd circle
			(at -0.40005 0 180)
			(size 0 0)
			(layers "F.Cu" "F.Mask" "F.Paste")
			(net "PVDD11_S3_P1_EN_R")
		)
		(pad "2" smd circle
			(at 0.40005 0 180)
			(size 0 0)
			(layers "F.Cu" "F.Mask" "F.Paste")
			(net "GND")
		)
	)
	(footprint ""
		(layer "F.Cu")
		(at 366.971326 -43.235118 -90)
		(property "Reference" "R814"
			(at 0 0 270)
			(layer "F.SilkS")
			(hide yes)
			(effects
				(font
					(size 1.27 1.27)
				)
			)
		)
		(property "Value" ""
			(at 0 0 270)
			(layer "F.Fab")
			(effects
				(font
					(size 1.27 1.27)
				)
			)
		)
		(duplicate_pad_numbers_are_jumpers no)
		(fp_line
			(start -0.7874 0.4064)
			(end -0.7874 -0.4064)
			(stroke
				(width 0.1524)
				(type default)
			)
			(layer "F.SilkS")
		)
		(fp_line
			(start 0.7874 0.4064)
			(end -0.7874 0.4064)
			(stroke
				(width 0.1524)
				(type default)
			)
			(layer "F.SilkS")
		)
		(fp_line
			(start -0.7874 -0.4064)
			(end 0.7874 -0.4064)
			(stroke
				(width 0.1524)
				(type default)
			)
			(layer "F.SilkS")
		)
		(fp_line
			(start 0.7874 -0.4064)
			(end 0.7874 0.4064)
			(stroke
				(width 0.1524)
				(type default)
			)
			(layer "F.SilkS")
		)
		(fp_line
			(start -0.67945 0.3048)
			(end -0.67945 -0.305054)
			(stroke
				(width 0.1)
				(type default)
			)
			(layer "F.Fab")
		)
		(fp_line
			(start -0.12065 0.3048)
			(end -0.67945 0.3048)
			(stroke
				(width 0.1)
				(type default)
			)
			(layer "F.Fab")
		)
		(fp_line
			(start 0.120396 0.3048)
			(end 0.120396 0.2794)
			(stroke
				(width 0.1)
				(type default)
			)
			(layer "F.Fab")
		)
		(fp_line
			(start 0.67945 0.3048)
			(end 0.120396 0.3048)
			(stroke
				(width 0.1)
				(type default)
			)
			(layer "F.Fab")
		)
		(fp_line
			(start -0.12065 0.2794)
			(end -0.12065 0.3048)
			(stroke
				(width 0.1)
				(type default)
			)
			(layer "F.Fab")
		)
		(fp_line
			(start 0.120396 0.2794)
			(end -0.12065 0.2794)
			(stroke
				(width 0.1)
				(type default)
			)
			(layer "F.Fab")
		)
		(fp_line
			(start -0.12065 -0.2794)
			(end 0.12065 -0.2794)
			(stroke
				(width 0.1)
				(type default)
			)
			(layer "F.Fab")
		)
		(fp_line
			(start 0.12065 -0.2794)
			(end 0.12065 -0.3048)
			(stroke
				(width 0.1)
				(type default)
			)
			(layer "F.Fab")
		)
		(fp_line
			(start 0.12065 -0.3048)
			(end 0.67945 -0.3048)
			(stroke
				(width 0.1)
				(type default)
			)
			(layer "F.Fab")
		)
		(fp_line
			(start 0.67945 -0.3048)
			(end 0.67945 0.3048)
			(stroke
				(width 0.1)
				(type default)
			)
			(layer "F.Fab")
		)
		(fp_line
			(start -0.67945 -0.305054)
			(end -0.12065 -0.305054)
			(stroke
				(width 0.1)
				(type default)
			)
			(layer "F.Fab")
		)
		(fp_line
			(start -0.12065 -0.305054)
			(end -0.12065 -0.2794)
			(stroke
				(width 0.1)
				(type default)
			)
			(layer "F.Fab")
		)
		(pad "1" smd circle
			(at -0.40005 0 270)
			(size 0 0)
			(layers "F.Cu" "F.Mask" "F.Paste")
			(net "PVDD18_S5_P0")
		)
		(pad "2" smd circle
			(at 0.40005 0 270)
			(size 0 0)
			(layers "F.Cu" "F.Mask" "F.Paste")
			(net "UART_CPU0_UART0_TX")
		)
	)
	(footprint ""
		(layer "F.Cu")
		(at 36.411662 -429.790098 90)
		(property "Reference" "R3285"
			(at 0 0 90)
			(layer "F.SilkS")
			(hide yes)
			(effects
				(font
					(size 1.27 1.27)
				)
			)
		)
		(property "Value" ""
			(at 0 0 90)
			(layer "F.Fab")
			(effects
				(font
					(size 1.27 1.27)
				)
			)
		)
		(duplicate_pad_numbers_are_jumpers no)
		(fp_line
			(start 0.7874 -0.4064)
			(end 0.7874 0.4064)
			(stroke
				(width 0.1524)
				(type default)
			)
			(layer "F.SilkS")
		)
		(fp_line
			(start -0.7874 -0.4064)
			(end 0.7874 -0.4064)
			(stroke
				(width 0.1524)
				(type default)
			)
			(layer "F.SilkS")
		)
		(fp_line
			(start 0.7874 0.4064)
			(end -0.7874 0.4064)
			(stroke
				(width 0.1524)
				(type default)
			)
			(layer "F.SilkS")
		)
		(fp_line
			(start -0.7874 0.4064)
			(end -0.7874 -0.4064)
			(stroke
				(width 0.1524)
				(type default)
			)
			(layer "F.SilkS")
		)
		(fp_line
			(start -0.12065 -0.305054)
			(end -0.12065 -0.2794)
			(stroke
				(width 0.1)
				(type default)
			)
			(layer "F.Fab")
		)
		(fp_line
			(start -0.67945 -0.305054)
			(end -0.12065 -0.305054)
			(stroke
				(width 0.1)
				(type default)
			)
			(layer "F.Fab")
		)
		(fp_line
			(start 0.67945 -0.3048)
			(end 0.67945 0.3048)
			(stroke
				(width 0.1)
				(type default)
			)
			(layer "F.Fab")
		)
		(fp_line
			(start 0.12065 -0.3048)
			(end 0.67945 -0.3048)
			(stroke
				(width 0.1)
				(type default)
			)
			(layer "F.Fab")
		)
		(fp_line
			(start 0.12065 -0.2794)
			(end 0.12065 -0.3048)
			(stroke
				(width 0.1)
				(type default)
			)
			(layer "F.Fab")
		)
		(fp_line
			(start -0.12065 -0.2794)
			(end 0.12065 -0.2794)
			(stroke
				(width 0.1)
				(type default)
			)
			(layer "F.Fab")
		)
		(fp_line
			(start 0.120396 0.2794)
			(end -0.12065 0.2794)
			(stroke
				(width 0.1)
				(type default)
			)
			(layer "F.Fab")
		)
		(fp_line
			(start -0.12065 0.2794)
			(end -0.12065 0.3048)
			(stroke
				(width 0.1)
				(type default)
			)
			(layer "F.Fab")
		)
		(fp_line
			(start 0.67945 0.3048)
			(end 0.120396 0.3048)
			(stroke
				(width 0.1)
				(type default)
			)
			(layer "F.Fab")
		)
		(fp_line
			(start 0.120396 0.3048)
			(end 0.120396 0.2794)
			(stroke
				(width 0.1)
				(type default)
			)
			(layer "F.Fab")
		)
		(fp_line
			(start -0.12065 0.3048)
			(end -0.67945 0.3048)
			(stroke
				(width 0.1)
				(type default)
			)
			(layer "F.Fab")
		)
		(fp_line
			(start -0.67945 0.3048)
			(end -0.67945 -0.305054)
			(stroke
				(width 0.1)
				(type default)
			)
			(layer "F.Fab")
		)
		(pad "1" smd circle
			(at -0.40005 0 90)
			(size 0 0)
			(layers "F.Cu" "F.Mask" "F.Paste")
			(net "FM_P2E_SWB")
		)
		(pad "2" smd circle
			(at 0.40005 0 90)
			(size 0 0)
			(layers "F.Cu" "F.Mask" "F.Paste")
			(net "GND")
		)
	)
	(footprint ""
		(layer "F.Cu")
		(at 43.14444 -101.74224)
		(property "Reference" "R855"
			(at 0 0 0)
			(layer "F.SilkS")
			(hide yes)
			(effects
				(font
					(size 1.27 1.27)
				)
			)
		)
		(property "Value" ""
			(at 0 0 0)
			(layer "F.Fab")
			(effects
				(font
					(size 1.27 1.27)
				)
			)
		)
		(duplicate_pad_numbers_are_jumpers no)
		(fp_line
			(start -0.7874 -0.4064)
			(end 0.7874 -0.4064)
			(stroke
				(width 0.1524)
				(type default)
			)
			(layer "F.SilkS")
		)
		(fp_line
			(start -0.7874 0.4064)
			(end -0.7874 -0.4064)
			(stroke
				(width 0.1524)
				(type default)
			)
			(layer "F.SilkS")
		)
		(fp_line
			(start 0.7874 -0.4064)
			(end 0.7874 0.4064)
			(stroke
				(width 0.1524)
				(type default)
			)
			(layer "F.SilkS")
		)
		(fp_line
			(start 0.7874 0.4064)
			(end -0.7874 0.4064)
			(stroke
				(width 0.1524)
				(type default)
			)
			(layer "F.SilkS")
		)
		(fp_line
			(start -0.67945 -0.305054)
			(end -0.12065 -0.305054)
			(stroke
				(width 0.1)
				(type default)
			)
			(layer "F.Fab")
		)
		(fp_line
			(start -0.67945 0.3048)
			(end -0.67945 -0.305054)
			(stroke
				(width 0.1)
				(type default)
			)
			(layer "F.Fab")
		)
		(fp_line
			(start -0.12065 -0.305054)
			(end -0.12065 -0.2794)
			(stroke
				(width 0.1)
				(type default)
			)
			(layer "F.Fab")
		)
		(fp_line
			(start -0.12065 -0.2794)
			(end 0.12065 -0.2794)
			(stroke
				(width 0.1)
				(type default)
			)
			(layer "F.Fab")
		)
		(fp_line
			(start -0.12065 0.2794)
			(end -0.12065 0.3048)
			(stroke
				(width 0.1)
				(type default)
			)
			(layer "F.Fab")
		)
		(fp_line
			(start -0.12065 0.3048)
			(end -0.67945 0.3048)
			(stroke
				(width 0.1)
				(type default)
			)
			(layer "F.Fab")
		)
		(fp_line
			(start 0.120396 0.2794)
			(end -0.12065 0.2794)
			(stroke
				(width 0.1)
				(type default)
			)
			(layer "F.Fab")
		)
		(fp_line
			(start 0.120396 0.3048)
			(end 0.120396 0.2794)
			(stroke
				(width 0.1)
				(type default)
			)
			(layer "F.Fab")
		)
		(fp_line
			(start 0.12065 -0.3048)
			(end 0.67945 -0.3048)
			(stroke
				(width 0.1)
				(type default)
			)
			(layer "F.Fab")
		)
		(fp_line
			(start 0.12065 -0.2794)
			(end 0.12065 -0.3048)
			(stroke
				(width 0.1)
				(type default)
			)
			(layer "F.Fab")
		)
		(fp_line
			(start 0.67945 -0.3048)
			(end 0.67945 0.3048)
			(stroke
				(width 0.1)
				(type default)
			)
			(layer "F.Fab")
		)
		(fp_line
			(start 0.67945 0.3048)
			(end 0.120396 0.3048)
			(stroke
				(width 0.1)
				(type default)
			)
			(layer "F.Fab")
		)
		(pad "1" smd circle
			(at -0.40005 0)
			(size 0 0)
			(layers "F.Cu" "F.Mask" "F.Paste")
			(net "P12V_AUX_DSC_VOL")
		)
		(pad "2" smd circle
			(at 0.40005 0)
			(size 0 0)
			(layers "F.Cu" "F.Mask" "F.Paste")
			(net "GND")
		)
	)
	(footprint ""
		(layer "F.Cu")
		(at 303.200308 -43.989498 180)
		(property "Reference" "C2052"
			(at 0 0 180)
			(layer "F.SilkS")
			(hide yes)
			(effects
				(font
					(size 1.27 1.27)
				)
			)
		)
		(property "Value" ""
			(at 0 0 180)
			(layer "F.Fab")
			(effects
				(font
					(size 1.27 1.27)
				)
			)
		)
		(duplicate_pad_numbers_are_jumpers no)
		(fp_line
			(start 0.7874 0.4064)
			(end -0.7874 0.4064)
			(stroke
				(width 0.1524)
				(type default)
			)
			(layer "F.SilkS")
		)
		(fp_line
			(start 0.7874 -0.4064)
			(end 0.7874 0.4064)
			(stroke
				(width 0.1524)
				(type default)
			)
			(layer "F.SilkS")
		)
		(fp_line
			(start -0.7874 0.4064)
			(end -0.7874 -0.4064)
			(stroke
				(width 0.1524)
				(type default)
			)
			(layer "F.SilkS")
		)
		(fp_line
			(start -0.7874 -0.4064)
			(end 0.7874 -0.4064)
			(stroke
				(width 0.1524)
				(type default)
			)
			(layer "F.SilkS")
		)
		(fp_line
			(start 0.67945 0.3048)
			(end 0.120396 0.3048)
			(stroke
				(width 0.1)
				(type default)
			)
			(layer "F.Fab")
		)
		(fp_line
			(start 0.67945 -0.3048)
			(end 0.67945 0.3048)
			(stroke
				(width 0.1)
				(type default)
			)
			(layer "F.Fab")
		)
		(fp_line
			(start 0.12065 -0.2794)
			(end 0.12065 -0.3048)
			(stroke
				(width 0.1)
				(type default)
			)
			(layer "F.Fab")
		)
		(fp_line
			(start 0.12065 -0.3048)
			(end 0.67945 -0.3048)
			(stroke
				(width 0.1)
				(type default)
			)
			(layer "F.Fab")
		)
		(fp_line
			(start 0.120396 0.3048)
			(end 0.120396 0.2794)
			(stroke
				(width 0.1)
				(type default)
			)
			(layer "F.Fab")
		)
		(fp_line
			(start 0.120396 0.2794)
			(end -0.12065 0.2794)
			(stroke
				(width 0.1)
				(type default)
			)
			(layer "F.Fab")
		)
		(fp_line
			(start -0.12065 0.3048)
			(end -0.67945 0.3048)
			(stroke
				(width 0.1)
				(type default)
			)
			(layer "F.Fab")
		)
		(fp_line
			(start -0.12065 0.2794)
			(end -0.12065 0.3048)
			(stroke
				(width 0.1)
				(type default)
			)
			(layer "F.Fab")
		)
		(fp_line
			(start -0.12065 -0.2794)
			(end 0.12065 -0.2794)
			(stroke
				(width 0.1)
				(type default)
			)
			(layer "F.Fab")
		)
		(fp_line
			(start -0.12065 -0.305054)
			(end -0.12065 -0.2794)
			(stroke
				(width 0.1)
				(type default)
			)
			(layer "F.Fab")
		)
		(fp_line
			(start -0.67945 0.3048)
			(end -0.67945 -0.305054)
			(stroke
				(width 0.1)
				(type default)
			)
			(layer "F.Fab")
		)
		(fp_line
			(start -0.67945 -0.305054)
			(end -0.12065 -0.305054)
			(stroke
				(width 0.1)
				(type default)
			)
			(layer "F.Fab")
		)
		(pad "1" smd circle
			(at -0.40005 0 180)
			(size 0 0)
			(layers "F.Cu" "F.Mask" "F.Paste")
			(net "P3V3_ADC128_VCC")
		)
		(pad "2" smd circle
			(at 0.40005 0 180)
			(size 0 0)
			(layers "F.Cu" "F.Mask" "F.Paste")
			(net "GND")
		)
	)
	(footprint ""
		(layer "F.Cu")
		(at 340.891876 -70.098412 90)
		(property "Reference" "D82"
			(at -3.934714 -0.691642 90)
			(unlocked yes)
			(layer "F.SilkS")
			(effects
				(font
					(size 0.7874 0.5842)
					(thickness 0.1524)
				)
				(justify left)
			)
		)
		(property "Value" ""
			(at 0 0 90)
			(layer "F.Fab")
			(effects
				(font
					(size 1.27 1.27)
				)
			)
		)
		(duplicate_pad_numbers_are_jumpers no)
		(fp_line
			(start 1.16078 -0.4826)
			(end 1.16078 0.4826)
			(stroke
				(width 0.1524)
				(type default)
			)
			(layer "F.SilkS")
		)
		(fp_line
			(start 1.03378 -0.4826)
			(end 1.03378 0.4826)
			(stroke
				(width 0.1524)
				(type default)
			)
			(layer "F.SilkS")
		)
		(fp_line
			(start 0.90678 -0.4826)
			(end 0.90678 0.4826)
			(stroke
				(width 0.1524)
				(type default)
			)
			(layer "F.SilkS")
		)
		(fp_line
			(start -0.64008 -0.4826)
			(end 1.16078 -0.4826)
			(stroke
				(width 0.1524)
				(type default)
			)
			(layer "F.SilkS")
		)
		(fp_line
			(start -0.79248 -0.4826)
			(end 1.03378 -0.4826)
			(stroke
				(width 0.1524)
				(type default)
			)
			(layer "F.SilkS")
		)
		(fp_line
			(start -0.89408 -0.4826)
			(end 0.90678 -0.4826)
			(stroke
				(width 0.1524)
				(type default)
			)
			(layer "F.SilkS")
		)
		(fp_line
			(start 1.16078 0.4826)
			(end -0.64008 0.4826)
			(stroke
				(width 0.1524)
				(type default)
			)
			(layer "F.SilkS")
		)
		(fp_line
			(start 1.03378 0.4826)
			(end -0.79248 0.4826)
			(stroke
				(width 0.1524)
				(type default)
			)
			(layer "F.SilkS")
		)
		(fp_line
			(start 0.90678 0.4826)
			(end -0.90678 0.4826)
			(stroke
				(width 0.1524)
				(type default)
			)
			(layer "F.SilkS")
		)
		(fp_line
			(start -0.90678 0.4826)
			(end -0.90678 -0.4699)
			(stroke
				(width 0.1524)
				(type default)
			)
			(layer "F.SilkS")
		)
		(fp_line
			(start 0.499872 -0.249936)
			(end 0.499872 0.249936)
			(stroke
				(width 0.1)
				(type default)
			)
			(layer "F.Fab")
		)
		(fp_line
			(start -0.499872 -0.249936)
			(end 0.499872 -0.249936)
			(stroke
				(width 0.1)
				(type default)
			)
			(layer "F.Fab")
		)
		(fp_line
			(start 0.499872 0.249936)
			(end -0.499872 0.249936)
			(stroke
				(width 0.1)
				(type default)
			)
			(layer "F.Fab")
		)
		(fp_line
			(start -0.499872 0.249936)
			(end -0.499872 -0.249936)
			(stroke
				(width 0.1)
				(type default)
			)
			(layer "F.Fab")
		)
		(pad "A" smd rect
			(at -0.47498 0 90)
			(size 0.6096 0.7112)
			(layers "F.Cu" "F.Mask" "F.Paste")
			(net "LED_PWRGD_PVDDCR_CPU1_P1_R")
		)
		(pad "C" smd rect
			(at 0.47498 0 90)
			(size 0.6096 0.7112)
			(layers "F.Cu" "F.Mask" "F.Paste")
			(net "LED_PWRGD_PVDDCR_CPU1_P1_D")
		)
	)
)
